(kicad_pcb
	(version 20260206)
	(generator "pcbnew")
	(generator_version "10.0")
	(general
		(thickness 1.6)
		(legacy_teardrops no)
	)
	(paper "A4")
	(title_block
		(title "01162023_DA0F0TEBIF0_F0T_Expander_BD_F_brd_V02_OCP.brd")
		(comment 1 "Grand Teton / footprints 644-651 of 9728")
	)
	(layers
		(0 "F.Cu" signal "TOP")
		(4 "In1.Cu" signal "GND")
		(6 "In2.Cu" signal "VCC")
		(8 "In3.Cu" signal "VCC1")
		(10 "In4.Cu" signal "GND1")
		(12 "In5.Cu" signal "IN1")
		(14 "In6.Cu" signal "GND2")
		(16 "In7.Cu" signal "IN2")
		(18 "In8.Cu" signal "GND3")
		(20 "In9.Cu" signal "IN3")
		(22 "In10.Cu" signal "GND4")
		(24 "In11.Cu" signal "IN4")
		(26 "In12.Cu" signal "GND5")
		(28 "In13.Cu" signal "IN5")
		(30 "In14.Cu" signal "GND6")
		(32 "In15.Cu" signal "IN6")
		(34 "In16.Cu" signal "GND7")
		(2 "B.Cu" signal "BOTTOM")
		(9 "F.Adhes" user "F.Adhesive")
		(11 "B.Adhes" user "B.Adhesive")
		(13 "F.Paste" user "Package Geometry/Pastemask Top")
		(15 "B.Paste" user "Package Geometry/Pastemask Bottom")
		(5 "F.SilkS" user "Ref Des/Silkscreen Top")
		(7 "B.SilkS" user "Ref Des/Silkscreen Bottom")
		(1 "F.Mask" user "Board Geometry/Soldermask Top")
		(3 "B.Mask" user "Board Geometry/Soldermask Bottom")
		(17 "Dwgs.User" user "User.Drawings")
		(19 "Cmts.User" user "User.Comments")
		(21 "Eco1.User" user "User.Eco1")
		(23 "Eco2.User" user "User.Eco2")
		(25 "Edge.Cuts" user "Board Geometry/Outline")
		(27 "Margin" user)
		(31 "F.CrtYd" user "Package Geometry/Place Bound Top")
		(29 "B.CrtYd" user "Package Geometry/Place Bound Bottom")
		(35 "F.Fab" user "Ref Des/Assembly Top")
		(33 "B.Fab" user "Ref Des/Assembly Bottom")
	)
	(footprint ""
		(layer "F.Cu")
		(at 98.659442 -61.612526)
		(property "Reference" "PD33"
			(at -3.7084 -2.733548 0)
			(unlocked yes)
			(layer "F.SilkS")
			(effects
				(font
					(size 0.7874 0.5842)
					(thickness 0.1524)
				)
				(justify left)
			)
		)
		(property "Value" ""
			(at 0 0 0)
			(layer "F.Fab")
			(effects
				(font
					(size 1.27 1.27)
				)
			)
		)
		(duplicate_pad_numbers_are_jumpers no)
		(fp_line
			(start -3.656584 -1.970024)
			(end -3.656584 1.970024)
			(stroke
				(width 0.1524)
				(type default)
			)
			(layer "F.SilkS")
		)
		(fp_line
			(start -3.656584 1.970024)
			(end 4.240784 1.970024)
			(stroke
				(width 0.1524)
				(type default)
			)
			(layer "F.SilkS")
		)
		(fp_line
			(start 4.240784 -1.970024)
			(end -3.656584 -1.970024)
			(stroke
				(width 0.1524)
				(type default)
			)
			(layer "F.SilkS")
		)
		(fp_line
			(start 4.240784 1.970024)
			(end 4.240784 -1.970024)
			(stroke
				(width 0.1524)
				(type default)
			)
			(layer "F.SilkS")
		)
		(fp_poly
			(pts
				(xy 3.580384 1.970024) (xy 3.580384 -1.970024) (xy 4.240784 -1.970024) (xy 4.240784 1.970024)
			)
			(stroke
				(width 0)
				(type default)
			)
			(fill yes)
			(layer "F.SilkS")
		)
		(fp_line
			(start -2.3749 -1.970024)
			(end -2.3749 1.970024)
			(stroke
				(width 0.1)
				(type default)
			)
			(layer "F.Fab")
		)
		(fp_line
			(start -2.3749 1.970024)
			(end 2.3749 1.970024)
			(stroke
				(width 0.1)
				(type default)
			)
			(layer "F.Fab")
		)
		(fp_line
			(start 2.3749 -1.970024)
			(end -2.3749 -1.970024)
			(stroke
				(width 0.1)
				(type default)
			)
			(layer "F.Fab")
		)
		(fp_line
			(start 2.3749 1.970024)
			(end 2.3749 -1.970024)
			(stroke
				(width 0.1)
				(type default)
			)
			(layer "F.Fab")
		)
		(fp_text user "+"
			(at -4.9784 -0.23495 0)
			(unlocked yes)
			(layer "F.Fab")
			(effects
				(font
					(size 1.905 1.4224)
					(thickness 0.1524)
				)
				(justify left)
			)
		)
		(fp_text user "-"
			(at 4.1656 -0.23495 0)
			(unlocked yes)
			(layer "F.Fab")
			(effects
				(font
					(size 1.905 1.4224)
					(thickness 0.1524)
				)
				(justify left)
			)
		)
		(pad "A" smd rect
			(at -2.450084 0)
			(size 2.159 2.2606)
			(layers "F.Cu" "F.Mask" "F.Paste")
			(net "GND")
		)
		(pad "C" smd rect
			(at 2.450084 0)
			(size 2.159 2.2606)
			(layers "F.Cu" "F.Mask" "F.Paste")
			(net "P12V_AUX")
		)
	)
	(footprint ""
		(layer "F.Cu")
		(at 163.390072 -72.766682 90)
		(property "Reference" "PR7066"
			(at 0 0 90)
			(layer "F.SilkS")
			(hide yes)
			(effects
				(font
					(size 1.27 1.27)
				)
			)
		)
		(property "Value" ""
			(at 0 0 90)
			(layer "F.Fab")
			(effects
				(font
					(size 1.27 1.27)
				)
			)
		)
		(duplicate_pad_numbers_are_jumpers no)
		(fp_line
			(start 0.7874 -0.4064)
			(end 0.7874 0.4064)
			(stroke
				(width 0.1524)
				(type default)
			)
			(layer "F.SilkS")
		)
		(fp_line
			(start -0.7874 -0.4064)
			(end 0.7874 -0.4064)
			(stroke
				(width 0.1524)
				(type default)
			)
			(layer "F.SilkS")
		)
		(fp_line
			(start 0.7874 0.4064)
			(end -0.7874 0.4064)
			(stroke
				(width 0.1524)
				(type default)
			)
			(layer "F.SilkS")
		)
		(fp_line
			(start -0.7874 0.4064)
			(end -0.7874 -0.4064)
			(stroke
				(width 0.1524)
				(type default)
			)
			(layer "F.SilkS")
		)
		(fp_line
			(start -0.12065 -0.305054)
			(end -0.12065 -0.2794)
			(stroke
				(width 0.1)
				(type default)
			)
			(layer "F.Fab")
		)
		(fp_line
			(start -0.67945 -0.305054)
			(end -0.12065 -0.305054)
			(stroke
				(width 0.1)
				(type default)
			)
			(layer "F.Fab")
		)
		(fp_line
			(start 0.67945 -0.3048)
			(end 0.67945 0.3048)
			(stroke
				(width 0.1)
				(type default)
			)
			(layer "F.Fab")
		)
		(fp_line
			(start 0.12065 -0.3048)
			(end 0.67945 -0.3048)
			(stroke
				(width 0.1)
				(type default)
			)
			(layer "F.Fab")
		)
		(fp_line
			(start 0.12065 -0.2794)
			(end 0.12065 -0.3048)
			(stroke
				(width 0.1)
				(type default)
			)
			(layer "F.Fab")
		)
		(fp_line
			(start -0.12065 -0.2794)
			(end 0.12065 -0.2794)
			(stroke
				(width 0.1)
				(type default)
			)
			(layer "F.Fab")
		)
		(fp_line
			(start 0.120396 0.2794)
			(end -0.12065 0.2794)
			(stroke
				(width 0.1)
				(type default)
			)
			(layer "F.Fab")
		)
		(fp_line
			(start -0.12065 0.2794)
			(end -0.12065 0.3048)
			(stroke
				(width 0.1)
				(type default)
			)
			(layer "F.Fab")
		)
		(fp_line
			(start 0.67945 0.3048)
			(end 0.120396 0.3048)
			(stroke
				(width 0.1)
				(type default)
			)
			(layer "F.Fab")
		)
		(fp_line
			(start 0.120396 0.3048)
			(end 0.120396 0.2794)
			(stroke
				(width 0.1)
				(type default)
			)
			(layer "F.Fab")
		)
		(fp_line
			(start -0.12065 0.3048)
			(end -0.67945 0.3048)
			(stroke
				(width 0.1)
				(type default)
			)
			(layer "F.Fab")
		)
		(fp_line
			(start -0.67945 0.3048)
			(end -0.67945 -0.305054)
			(stroke
				(width 0.1)
				(type default)
			)
			(layer "F.Fab")
		)
		(pad "1" smd circle
			(at -0.40005 0 90)
			(size 0 0)
			(layers "F.Cu" "F.Mask" "F.Paste")
			(net "P12V_SSD5_CO_ILIMIT")
		)
		(pad "2" smd circle
			(at 0.40005 0 90)
			(size 0 0)
			(layers "F.Cu" "F.Mask" "F.Paste")
			(net "GND")
		)
	)
	(footprint ""
		(layer "F.Cu")
		(at 403.082506 -29.875734)
		(property "Reference" "PU133"
			(at -3.015996 -2.166366 90)
			(unlocked yes)
			(layer "F.SilkS")
			(effects
				(font
					(size 0.7874 0.5842)
					(thickness 0.1524)
				)
			)
		)
		(property "Value" ""
			(at 0 0 0)
			(layer "F.Fab")
			(effects
				(font
					(size 1.27 1.27)
				)
			)
		)
		(duplicate_pad_numbers_are_jumpers no)
		(fp_line
			(start -1.239774 -1.495298)
			(end 1.239774 -1.495298)
			(stroke
				(width 0.1524)
				(type default)
			)
			(layer "F.SilkS")
		)
		(fp_line
			(start -1.239774 1.495298)
			(end -1.239774 -1.495298)
			(stroke
				(width 0.1524)
				(type default)
			)
			(layer "F.SilkS")
		)
		(fp_line
			(start 1.239774 -1.495298)
			(end 1.239774 1.495298)
			(stroke
				(width 0.1524)
				(type default)
			)
			(layer "F.SilkS")
		)
		(fp_line
			(start 1.239774 1.495298)
			(end -1.239774 1.495298)
			(stroke
				(width 0.1524)
				(type default)
			)
			(layer "F.SilkS")
		)
		(fp_poly
			(pts
				(xy -1.965706 -1.257046) (xy -2.684018 -0.538734) (xy -1.60655 -0.179578)
			)
			(stroke
				(width 0)
				(type default)
			)
			(fill yes)
			(layer "F.SilkS")
		)
		(fp_line
			(start -0.8001 -1.050036)
			(end 0.8001 -1.050036)
			(stroke
				(width 0.1)
				(type default)
			)
			(layer "F.Fab")
		)
		(fp_line
			(start -0.8001 1.050036)
			(end -0.8001 -1.050036)
			(stroke
				(width 0.1)
				(type default)
			)
			(layer "F.Fab")
		)
		(fp_line
			(start 0.8001 -1.050036)
			(end 0.8001 1.050036)
			(stroke
				(width 0.1)
				(type default)
			)
			(layer "F.Fab")
		)
		(fp_line
			(start 0.8001 1.050036)
			(end -0.8001 1.050036)
			(stroke
				(width 0.1)
				(type default)
			)
			(layer "F.Fab")
		)
		(fp_poly
			(pts
				(xy -2.458974 -0.508) (xy -2.458974 0.508) (xy -1.442974 0)
			)
			(stroke
				(width 0)
				(type default)
			)
			(fill yes)
			(layer "F.Fab")
		)
		(pad "1_2" smd circle
			(at -0.374904 0 90)
			(size 0 0)
			(layers "F.Cu" "F.Mask" "F.Paste")
			(net "P3V3_AUX")
		)
		(pad "3" smd rect
			(at -0.499872 0.999998)
			(size 0.254 0.7112)
			(layers "F.Cu" "F.Mask" "F.Paste")
			(net "GND")
		)
		(pad "4" smd rect
			(at 0 0.999998)
			(size 0.254 0.7112)
			(layers "F.Cu" "F.Mask" "F.Paste")
			(net "P3V3_SSD14_CO_ILIMIT")
		)
		(pad "5" smd rect
			(at 0.499872 0.999998)
			(size 0.254 0.7112)
			(layers "F.Cu" "F.Mask" "F.Paste")
			(net "P3V3_SSD14_CO_MODE")
		)
		(pad "6_7" smd circle
			(at 0.374904 0 270)
			(size 0 0)
			(layers "F.Cu" "F.Mask" "F.Paste")
			(net "P3V3_SSD14")
		)
		(pad "8" smd rect
			(at 0.499872 -0.999998)
			(size 0.254 0.7112)
			(layers "F.Cu" "F.Mask" "F.Paste")
			(net "P3V3_SSD14_CO_GATE")
		)
		(pad "9" smd rect
			(at 0 -0.999998)
			(size 0.254 0.7112)
			(layers "F.Cu" "F.Mask" "F.Paste")
			(net "P3V3_SSD14_CO_EN")
		)
		(pad "10" smd rect
			(at -0.499872 -0.999998)
			(size 0.254 0.7112)
			(layers "F.Cu" "F.Mask" "F.Paste")
			(net "P3V3_SSD14_CO_DV_DT")
		)
	)
	(footprint ""
		(layer "F.Cu")
		(at 407.295096 -100.766372 180)
		(property "Reference" "R384"
			(at 0 0 180)
			(layer "F.SilkS")
			(hide yes)
			(effects
				(font
					(size 1.27 1.27)
				)
			)
		)
		(property "Value" ""
			(at 0 0 180)
			(layer "F.Fab")
			(effects
				(font
					(size 1.27 1.27)
				)
			)
		)
		(duplicate_pad_numbers_are_jumpers no)
		(fp_line
			(start 0.7874 0.4064)
			(end -0.7874 0.4064)
			(stroke
				(width 0.1524)
				(type default)
			)
			(layer "F.SilkS")
		)
		(fp_line
			(start 0.7874 -0.4064)
			(end 0.7874 0.4064)
			(stroke
				(width 0.1524)
				(type default)
			)
			(layer "F.SilkS")
		)
		(fp_line
			(start -0.7874 0.4064)
			(end -0.7874 -0.4064)
			(stroke
				(width 0.1524)
				(type default)
			)
			(layer "F.SilkS")
		)
		(fp_line
			(start -0.7874 -0.4064)
			(end 0.7874 -0.4064)
			(stroke
				(width 0.1524)
				(type default)
			)
			(layer "F.SilkS")
		)
		(fp_line
			(start 0.67945 0.3048)
			(end 0.120396 0.3048)
			(stroke
				(width 0.1)
				(type default)
			)
			(layer "F.Fab")
		)
		(fp_line
			(start 0.67945 -0.3048)
			(end 0.67945 0.3048)
			(stroke
				(width 0.1)
				(type default)
			)
			(layer "F.Fab")
		)
		(fp_line
			(start 0.12065 -0.2794)
			(end 0.12065 -0.3048)
			(stroke
				(width 0.1)
				(type default)
			)
			(layer "F.Fab")
		)
		(fp_line
			(start 0.12065 -0.3048)
			(end 0.67945 -0.3048)
			(stroke
				(width 0.1)
				(type default)
			)
			(layer "F.Fab")
		)
		(fp_line
			(start 0.120396 0.3048)
			(end 0.120396 0.2794)
			(stroke
				(width 0.1)
				(type default)
			)
			(layer "F.Fab")
		)
		(fp_line
			(start 0.120396 0.2794)
			(end -0.12065 0.2794)
			(stroke
				(width 0.1)
				(type default)
			)
			(layer "F.Fab")
		)
		(fp_line
			(start -0.12065 0.3048)
			(end -0.67945 0.3048)
			(stroke
				(width 0.1)
				(type default)
			)
			(layer "F.Fab")
		)
		(fp_line
			(start -0.12065 0.2794)
			(end -0.12065 0.3048)
			(stroke
				(width 0.1)
				(type default)
			)
			(layer "F.Fab")
		)
		(fp_line
			(start -0.12065 -0.2794)
			(end 0.12065 -0.2794)
			(stroke
				(width 0.1)
				(type default)
			)
			(layer "F.Fab")
		)
		(fp_line
			(start -0.12065 -0.305054)
			(end -0.12065 -0.2794)
			(stroke
				(width 0.1)
				(type default)
			)
			(layer "F.Fab")
		)
		(fp_line
			(start -0.67945 0.3048)
			(end -0.67945 -0.305054)
			(stroke
				(width 0.1)
				(type default)
			)
			(layer "F.Fab")
		)
		(fp_line
			(start -0.67945 -0.305054)
			(end -0.12065 -0.305054)
			(stroke
				(width 0.1)
				(type default)
			)
			(layer "F.Fab")
		)
		(pad "1" smd circle
			(at -0.40005 0 180)
			(size 0 0)
			(layers "F.Cu" "F.Mask" "F.Paste")
			(net "NIC7_SLOT_ID1")
		)
		(pad "2" smd circle
			(at 0.40005 0 180)
			(size 0 0)
			(layers "F.Cu" "F.Mask" "F.Paste")
			(net "P3V3_NIC7")
		)
	)
	(footprint ""
		(layer "F.Cu")
		(at 24.342344 -252.356874 -90)
		(property "Reference" "R1215"
			(at 0 0 270)
			(layer "F.SilkS")
			(hide yes)
			(effects
				(font
					(size 1.27 1.27)
				)
			)
		)
		(property "Value" ""
			(at 0 0 270)
			(layer "F.Fab")
			(effects
				(font
					(size 1.27 1.27)
				)
			)
		)
		(duplicate_pad_numbers_are_jumpers no)
		(fp_line
			(start -0.7874 0.4064)
			(end -0.7874 -0.4064)
			(stroke
				(width 0.1524)
				(type default)
			)
			(layer "F.SilkS")
		)
		(fp_line
			(start 0.7874 0.4064)
			(end -0.7874 0.4064)
			(stroke
				(width 0.1524)
				(type default)
			)
			(layer "F.SilkS")
		)
		(fp_line
			(start -0.7874 -0.4064)
			(end 0.7874 -0.4064)
			(stroke
				(width 0.1524)
				(type default)
			)
			(layer "F.SilkS")
		)
		(fp_line
			(start 0.7874 -0.4064)
			(end 0.7874 0.4064)
			(stroke
				(width 0.1524)
				(type default)
			)
			(layer "F.SilkS")
		)
		(fp_line
			(start -0.67945 0.3048)
			(end -0.67945 -0.305054)
			(stroke
				(width 0.1)
				(type default)
			)
			(layer "F.Fab")
		)
		(fp_line
			(start -0.12065 0.3048)
			(end -0.67945 0.3048)
			(stroke
				(width 0.1)
				(type default)
			)
			(layer "F.Fab")
		)
		(fp_line
			(start 0.120396 0.3048)
			(end 0.120396 0.2794)
			(stroke
				(width 0.1)
				(type default)
			)
			(layer "F.Fab")
		)
		(fp_line
			(start 0.67945 0.3048)
			(end 0.120396 0.3048)
			(stroke
				(width 0.1)
				(type default)
			)
			(layer "F.Fab")
		)
		(fp_line
			(start -0.12065 0.2794)
			(end -0.12065 0.3048)
			(stroke
				(width 0.1)
				(type default)
			)
			(layer "F.Fab")
		)
		(fp_line
			(start 0.120396 0.2794)
			(end -0.12065 0.2794)
			(stroke
				(width 0.1)
				(type default)
			)
			(layer "F.Fab")
		)
		(fp_line
			(start -0.12065 -0.2794)
			(end 0.12065 -0.2794)
			(stroke
				(width 0.1)
				(type default)
			)
			(layer "F.Fab")
		)
		(fp_line
			(start 0.12065 -0.2794)
			(end 0.12065 -0.3048)
			(stroke
				(width 0.1)
				(type default)
			)
			(layer "F.Fab")
		)
		(fp_line
			(start 0.12065 -0.3048)
			(end 0.67945 -0.3048)
			(stroke
				(width 0.1)
				(type default)
			)
			(layer "F.Fab")
		)
		(fp_line
			(start 0.67945 -0.3048)
			(end 0.67945 0.3048)
			(stroke
				(width 0.1)
				(type default)
			)
			(layer "F.Fab")
		)
		(fp_line
			(start -0.67945 -0.305054)
			(end -0.12065 -0.305054)
			(stroke
				(width 0.1)
				(type default)
			)
			(layer "F.Fab")
		)
		(fp_line
			(start -0.12065 -0.305054)
			(end -0.12065 -0.2794)
			(stroke
				(width 0.1)
				(type default)
			)
			(layer "F.Fab")
		)
		(pad "1" smd circle
			(at -0.40005 0 270)
			(size 0 0)
			(layers "F.Cu" "F.Mask" "F.Paste")
			(net "GND")
		)
		(pad "2" smd circle
			(at 0.40005 0 270)
			(size 0 0)
			(layers "F.Cu" "F.Mask" "F.Paste")
			(net "PEX0_MODE_SEL9")
		)
	)
	(footprint ""
		(layer "F.Cu")
		(at 402.25218 -350.098614 90)
		(property "Reference" "C746"
			(at 0 0 90)
			(layer "F.SilkS")
			(hide yes)
			(effects
				(font
					(size 1.27 1.27)
				)
			)
		)
		(property "Value" ""
			(at 0 0 90)
			(layer "F.Fab")
			(effects
				(font
					(size 1.27 1.27)
				)
			)
		)
		(duplicate_pad_numbers_are_jumpers no)
		(fp_line
			(start 0.299974 -0.150114)
			(end 0.299974 0.150114)
			(stroke
				(width 0.1)
				(type default)
			)
			(layer "F.Fab")
		)
		(fp_line
			(start -0.299974 -0.150114)
			(end 0.299974 -0.150114)
			(stroke
				(width 0.1)
				(type default)
			)
			(layer "F.Fab")
		)
		(fp_line
			(start 0.299974 0.150114)
			(end -0.299974 0.150114)
			(stroke
				(width 0.1)
				(type default)
			)
			(layer "F.Fab")
		)
		(fp_line
			(start -0.299974 0.150114)
			(end -0.299974 -0.150114)
			(stroke
				(width 0.1)
				(type default)
			)
			(layer "F.Fab")
		)
		(pad "1" smd rect
			(at -0.2667 0 90)
			(size 0.3048 0.381)
			(layers "F.Cu" "F.Mask" "F.Paste")
			(net "P5E_PEX3_STN5_TX_DP<87>")
		)
		(pad "2" smd rect
			(at 0.2667 0 90)
			(size 0.3048 0.381)
			(layers "F.Cu" "F.Mask" "F.Paste")
			(net "P5E_PEX3_STN5_TX_C_DP<87>")
		)
	)
	(footprint ""
		(layer "F.Cu")
		(at 304.634392 -30.03169 180)
		(property "Reference" "C508"
			(at 0 0 180)
			(layer "F.SilkS")
			(hide yes)
			(effects
				(font
					(size 1.27 1.27)
				)
			)
		)
		(property "Value" ""
			(at 0 0 180)
			(layer "F.Fab")
			(effects
				(font
					(size 1.27 1.27)
				)
			)
		)
		(duplicate_pad_numbers_are_jumpers no)
		(fp_line
			(start 0.299974 0.150114)
			(end -0.299974 0.150114)
			(stroke
				(width 0.1)
				(type default)
			)
			(layer "F.Fab")
		)
		(fp_line
			(start 0.299974 -0.150114)
			(end 0.299974 0.150114)
			(stroke
				(width 0.1)
				(type default)
			)
			(layer "F.Fab")
		)
		(fp_line
			(start -0.299974 0.150114)
			(end -0.299974 -0.150114)
			(stroke
				(width 0.1)
				(type default)
			)
			(layer "F.Fab")
		)
		(fp_line
			(start -0.299974 -0.150114)
			(end 0.299974 -0.150114)
			(stroke
				(width 0.1)
				(type default)
			)
			(layer "F.Fab")
		)
		(pad "1" smd rect
			(at -0.2667 0 180)
			(size 0.3048 0.381)
			(layers "F.Cu" "F.Mask" "F.Paste")
			(net "P5E_PEX2_STN2_TX_DN<37>")
		)
		(pad "2" smd rect
			(at 0.2667 0 180)
			(size 0.3048 0.381)
			(layers "F.Cu" "F.Mask" "F.Paste")
			(net "P5E_PEX2_STN2_TX_C_DN<37>")
		)
	)
	(footprint ""
		(layer "F.Cu")
		(at 304.634392 -30.94609 180)
		(property "Reference" "C507"
			(at 0 0 180)
			(layer "F.SilkS")
			(hide yes)
			(effects
				(font
					(size 1.27 1.27)
				)
			)
		)
		(property "Value" ""
			(at 0 0 180)
			(layer "F.Fab")
			(effects
				(font
					(size 1.27 1.27)
				)
			)
		)
		(duplicate_pad_numbers_are_jumpers no)
		(fp_line
			(start 0.299974 0.150114)
			(end -0.299974 0.150114)
			(stroke
				(width 0.1)
				(type default)
			)
			(layer "F.Fab")
		)
		(fp_line
			(start 0.299974 -0.150114)
			(end 0.299974 0.150114)
			(stroke
				(width 0.1)
				(type default)
			)
			(layer "F.Fab")
		)
		(fp_line
			(start -0.299974 0.150114)
			(end -0.299974 -0.150114)
			(stroke
				(width 0.1)
				(type default)
			)
			(layer "F.Fab")
		)
		(fp_line
			(start -0.299974 -0.150114)
			(end 0.299974 -0.150114)
			(stroke
				(width 0.1)
				(type default)
			)
			(layer "F.Fab")
		)
		(pad "1" smd rect
			(at -0.2667 0 180)
			(size 0.3048 0.381)
			(layers "F.Cu" "F.Mask" "F.Paste")
			(net "P5E_PEX2_STN2_TX_DP<37>")
		)
		(pad "2" smd rect
			(at 0.2667 0 180)
			(size 0.3048 0.381)
			(layers "F.Cu" "F.Mask" "F.Paste")
			(net "P5E_PEX2_STN2_TX_C_DP<37>")
		)
	)
)
